# T6G (Grand Teton) — schematic netlist excerpt (pin names and nets, part order shuffled) for the footprints in the layout excerpt that follows; sources: Cadence DE-HDL packaged netlist, KiCad conversion of 04192023_DAF0TMB3IC0_F0TG_MB_C_brd_V02_OCP.brd

PC2174  Q_CAP  0.1UF 25V 10% X7R  pkg 0402  page 141 : A = P12V_OCP_V3_2 ; B = GND
C707  Q_CAP_DIFFBUS  DIFF BUS_0.22UF 6.3V 20% X6S  pkg C0201  page 67 : \1\ = P5E_CPU1_G1_TX_C_DP<1> ; \2\ = P5E_CPU1_G1_TX_DP<1>
R6207  Q_RES  10K 1% CHIP  pkg 0402LF  page 176 : A = P3V3_AUX ; B = PU_CPU0_USB_HUB_RESERVED1

(kicad_pcb
	(version 20260206)
	(generator "pcbnew")
	(generator_version "10.0")
	(general
		(thickness 1.6)
		(legacy_teardrops no)
	)
	(paper "A4")
	(title_block
		(title "04192023_DAF0TMB3IC0_F0TG_MB_C_brd_V02_OCP.brd")
		(comment 1 "Grand Teton / footprints 218-220 of 8354")
	)
	(layers
		(0 "F.Cu" signal "TOP")
		(4 "In1.Cu" signal "GND")
		(6 "In2.Cu" signal "IN1")
		(8 "In3.Cu" signal "GND1")
		(10 "In4.Cu" signal "IN2")
		(12 "In5.Cu" signal "GND2")
		(14 "In6.Cu" signal "IN3")
		(16 "In7.Cu" signal "GND3")
		(18 "In8.Cu" signal "VCC")
		(20 "In9.Cu" signal "VCC1")
		(22 "In10.Cu" signal "GND4")
		(24 "In11.Cu" signal "IN4")
		(26 "In12.Cu" signal "GND5")
		(28 "In13.Cu" signal "IN5")
		(30 "In14.Cu" signal "GND6")
		(32 "In15.Cu" signal "IN6")
		(34 "In16.Cu" signal "GND7")
		(2 "B.Cu" signal "BOTTOM")
		(9 "F.Adhes" user "F.Adhesive")
		(11 "B.Adhes" user "B.Adhesive")
		(13 "F.Paste" user "Package Geometry/Pastemask Top")
		(15 "B.Paste" user "Package Geometry/Pastemask Bottom")
		(5 "F.SilkS" user "Ref Des/Silkscreen Top")
		(7 "B.SilkS" user "Ref Des/Silkscreen Bottom")
		(1 "F.Mask" user "Board Geometry/Soldermask Top")
		(3 "B.Mask" user "Board Geometry/Soldermask Bottom")
		(17 "Dwgs.User" user "User.Drawings")
		(19 "Cmts.User" user "User.Comments")
		(21 "Eco1.User" user "User.Eco1")
		(23 "Eco2.User" user "User.Eco2")
		(25 "Edge.Cuts" user "Board Geometry/Outline")
		(27 "Margin" user)
		(31 "F.CrtYd" user "Package Geometry/Place Bound Top")
		(29 "B.CrtYd" user "Package Geometry/Place Bound Bottom")
		(35 "F.Fab" user "Ref Des/Assembly Top")
		(33 "B.Fab" user "Ref Des/Assembly Bottom")
	)
	(footprint ""
		(layer "F.Cu")
		(at 69.917818 -25.192482)
		(property "Reference" "PC2174"
			(at 0 0 0)
			(layer "F.SilkS")
			(hide yes)
			(effects
				(font
					(size 1.27 1.27)
				)
			)
		)
		(property "Value" ""
			(at 0 0 0)
			(layer "F.Fab")
			(effects
				(font
					(size 1.27 1.27)
				)
			)
		)
		(duplicate_pad_numbers_are_jumpers no)
		(fp_line
			(start -0.7874 -0.4064)
			(end 0.7874 -0.4064)
			(stroke
				(width 0.1524)
				(type default)
			)
			(layer "F.SilkS")
		)
		(fp_line
			(start -0.7874 0.4064)
			(end -0.7874 -0.4064)
			(stroke
				(width 0.1524)
				(type default)
			)
			(layer "F.SilkS")
		)
		(fp_line
			(start 0.7874 -0.4064)
			(end 0.7874 0.4064)
			(stroke
				(width 0.1524)
				(type default)
			)
			(layer "F.SilkS")
		)
		(fp_line
			(start 0.7874 0.4064)
			(end -0.7874 0.4064)
			(stroke
				(width 0.1524)
				(type default)
			)
			(layer "F.SilkS")
		)
		(fp_line
			(start -0.67945 -0.305054)
			(end -0.12065 -0.305054)
			(stroke
				(width 0.1)
				(type default)
			)
			(layer "F.Fab")
		)
		(fp_line
			(start -0.67945 0.3048)
			(end -0.67945 -0.305054)
			(stroke
				(width 0.1)
				(type default)
			)
			(layer "F.Fab")
		)
		(fp_line
			(start -0.12065 -0.305054)
			(end -0.12065 -0.2794)
			(stroke
				(width 0.1)
				(type default)
			)
			(layer "F.Fab")
		)
		(fp_line
			(start -0.12065 -0.2794)
			(end 0.12065 -0.2794)
			(stroke
				(width 0.1)
				(type default)
			)
			(layer "F.Fab")
		)
		(fp_line
			(start -0.12065 0.2794)
			(end -0.12065 0.3048)
			(stroke
				(width 0.1)
				(type default)
			)
			(layer "F.Fab")
		)
		(fp_line
			(start -0.12065 0.3048)
			(end -0.67945 0.3048)
			(stroke
				(width 0.1)
				(type default)
			)
			(layer "F.Fab")
		)
		(fp_line
			(start 0.120396 0.2794)
			(end -0.12065 0.2794)
			(stroke
				(width 0.1)
				(type default)
			)
			(layer "F.Fab")
		)
		(fp_line
			(start 0.120396 0.3048)
			(end 0.120396 0.2794)
			(stroke
				(width 0.1)
				(type default)
			)
			(layer "F.Fab")
		)
		(fp_line
			(start 0.12065 -0.3048)
			(end 0.67945 -0.3048)
			(stroke
				(width 0.1)
				(type default)
			)
			(layer "F.Fab")
		)
		(fp_line
			(start 0.12065 -0.2794)
			(end 0.12065 -0.3048)
			(stroke
				(width 0.1)
				(type default)
			)
			(layer "F.Fab")
		)
		(fp_line
			(start 0.67945 -0.3048)
			(end 0.67945 0.3048)
			(stroke
				(width 0.1)
				(type default)
			)
			(layer "F.Fab")
		)
		(fp_line
			(start 0.67945 0.3048)
			(end 0.120396 0.3048)
			(stroke
				(width 0.1)
				(type default)
			)
			(layer "F.Fab")
		)
		(pad "1" smd circle
			(at -0.40005 0)
			(size 0 0)
			(layers "F.Cu" "F.Mask" "F.Paste")
			(net "P12V_OCP_V3_2")
		)
		(pad "2" smd circle
			(at 0.40005 0)
			(size 0 0)
			(layers "F.Cu" "F.Mask" "F.Paste")
			(net "GND")
		)
	)
	(footprint ""
		(layer "F.Cu")
		(at 139.749784 -47.309024 -90)
		(property "Reference" "R6207"
			(at 0 0 270)
			(layer "F.SilkS")
			(hide yes)
			(effects
				(font
					(size 1.27 1.27)
				)
			)
		)
		(property "Value" ""
			(at 0 0 270)
			(layer "F.Fab")
			(effects
				(font
					(size 1.27 1.27)
				)
			)
		)
		(duplicate_pad_numbers_are_jumpers no)
		(fp_line
			(start -0.7874 0.4064)
			(end -0.7874 -0.4064)
			(stroke
				(width 0.1524)
				(type default)
			)
			(layer "F.SilkS")
		)
		(fp_line
			(start 0.7874 0.4064)
			(end -0.7874 0.4064)
			(stroke
				(width 0.1524)
				(type default)
			)
			(layer "F.SilkS")
		)
		(fp_line
			(start -0.7874 -0.4064)
			(end 0.7874 -0.4064)
			(stroke
				(width 0.1524)
				(type default)
			)
			(layer "F.SilkS")
		)
		(fp_line
			(start 0.7874 -0.4064)
			(end 0.7874 0.4064)
			(stroke
				(width 0.1524)
				(type default)
			)
			(layer "F.SilkS")
		)
		(fp_line
			(start -0.67945 0.3048)
			(end -0.67945 -0.305054)
			(stroke
				(width 0.1)
				(type default)
			)
			(layer "F.Fab")
		)
		(fp_line
			(start -0.12065 0.3048)
			(end -0.67945 0.3048)
			(stroke
				(width 0.1)
				(type default)
			)
			(layer "F.Fab")
		)
		(fp_line
			(start 0.120396 0.3048)
			(end 0.120396 0.2794)
			(stroke
				(width 0.1)
				(type default)
			)
			(layer "F.Fab")
		)
		(fp_line
			(start 0.67945 0.3048)
			(end 0.120396 0.3048)
			(stroke
				(width 0.1)
				(type default)
			)
			(layer "F.Fab")
		)
		(fp_line
			(start -0.12065 0.2794)
			(end -0.12065 0.3048)
			(stroke
				(width 0.1)
				(type default)
			)
			(layer "F.Fab")
		)
		(fp_line
			(start 0.120396 0.2794)
			(end -0.12065 0.2794)
			(stroke
				(width 0.1)
				(type default)
			)
			(layer "F.Fab")
		)
		(fp_line
			(start -0.12065 -0.2794)
			(end 0.12065 -0.2794)
			(stroke
				(width 0.1)
				(type default)
			)
			(layer "F.Fab")
		)
		(fp_line
			(start 0.12065 -0.2794)
			(end 0.12065 -0.3048)
			(stroke
				(width 0.1)
				(type default)
			)
			(layer "F.Fab")
		)
		(fp_line
			(start 0.12065 -0.3048)
			(end 0.67945 -0.3048)
			(stroke
				(width 0.1)
				(type default)
			)
			(layer "F.Fab")
		)
		(fp_line
			(start 0.67945 -0.3048)
			(end 0.67945 0.3048)
			(stroke
				(width 0.1)
				(type default)
			)
			(layer "F.Fab")
		)
		(fp_line
			(start -0.67945 -0.305054)
			(end -0.12065 -0.305054)
			(stroke
				(width 0.1)
				(type default)
			)
			(layer "F.Fab")
		)
		(fp_line
			(start -0.12065 -0.305054)
			(end -0.12065 -0.2794)
			(stroke
				(width 0.1)
				(type default)
			)
			(layer "F.Fab")
		)
		(pad "1" smd circle
			(at -0.40005 0 270)
			(size 0 0)
			(layers "F.Cu" "F.Mask" "F.Paste")
			(net "P3V3_AUX")
		)
		(pad "2" smd circle
			(at 0.40005 0 270)
			(size 0 0)
			(layers "F.Cu" "F.Mask" "F.Paste")
			(net "PU_CPU0_USB_HUB_RESERVED1")
		)
	)
	(footprint ""
		(layer "F.Cu")
		(at 55.87873 -16.099536 90)
		(property "Reference" "C707"
			(at 0 0 90)
			(layer "F.SilkS")
			(hide yes)
			(effects
				(font
					(size 1.27 1.27)
				)
			)
		)
		(property "Value" ""
			(at 0 0 90)
			(layer "F.Fab")
			(effects
				(font
					(size 1.27 1.27)
				)
			)
		)
		(duplicate_pad_numbers_are_jumpers no)
		(fp_line
			(start 0.299974 -0.150114)
			(end 0.299974 0.150114)
			(stroke
				(width 0.1)
				(type default)
			)
			(layer "F.Fab")
		)
		(fp_line
			(start -0.299974 -0.150114)
			(end 0.299974 -0.150114)
			(stroke
				(width 0.1)
				(type default)
			)
			(layer "F.Fab")
		)
		(fp_line
			(start 0.299974 0.150114)
			(end -0.299974 0.150114)
			(stroke
				(width 0.1)
				(type default)
			)
			(layer "F.Fab")
		)
		(fp_line
			(start -0.299974 0.150114)
			(end -0.299974 -0.150114)
			(stroke
				(width 0.1)
				(type default)
			)
			(layer "F.Fab")
		)
		(pad "1" smd rect
			(at -0.2667 0 90)
			(size 0.3048 0.381)
			(layers "F.Cu" "F.Mask" "F.Paste")
			(net "P5E_CPU1_G1_TX_C_DP<1>")
		)
		(pad "2" smd rect
			(at 0.2667 0 90)
			(size 0.3048 0.381)
			(layers "F.Cu" "F.Mask" "F.Paste")
			(net "P5E_CPU1_G1_TX_DP<1>")
		)
	)
)
